# BASEBOARD_FAB2 (Tioga Pass) — schematic netlist excerpt (pin names and nets, part order shuffled) for the footprints in the layout excerpt that follows; sources: Cadence DE-HDL packaged netlist, KiCad conversion of Wiwynn_Tioga_Pass_MB.brd

R7M4  RES  20.0 1% CHIP  pkg 0402  page 99 : A = SMB_DDR_KLM_VPP_SCL_R ; B = SMB_DDR_KLM_VPP_SCL
C2T4  CAP_A  0.1UF 16V 10% X7R  pkg 0402V  page 185 : A = P3V3 ; B = GND
C2P5  CAP_A  0.1UF 16V 10% X7R  pkg 0402V  page 192 : A = P3V3_STBY ; B = GND

(kicad_pcb
	(version 20260206)
	(generator "pcbnew")
	(generator_version "10.0")
	(general
		(thickness 1.6)
		(legacy_teardrops no)
	)
	(paper "A4")
	(title_block
		(title "Wiwynn_Tioga_Pass_MB.brd")
		(comment 1 "Tioga Pass / footprints 4264-4266 of 4770")
	)
	(layers
		(0 "F.Cu" signal "TOP")
		(4 "In1.Cu" signal "L2GND")
		(6 "In2.Cu" signal "L3")
		(8 "In3.Cu" signal "L4GND")
		(10 "In4.Cu" signal "L5")
		(12 "In5.Cu" signal "L6GND")
		(14 "In6.Cu" signal "L7VCC")
		(16 "In7.Cu" signal "L8VCC")
		(18 "In8.Cu" signal "L9GND")
		(20 "In9.Cu" signal "L10")
		(22 "In10.Cu" signal "L11GND")
		(24 "In11.Cu" signal "L12")
		(26 "In12.Cu" signal "L13GND")
		(2 "B.Cu" signal "BOTTOM")
		(9 "F.Adhes" user "F.Adhesive")
		(11 "B.Adhes" user "B.Adhesive")
		(13 "F.Paste" user "Package Geometry/Pastemask Top")
		(15 "B.Paste" user "Package Geometry/Pastemask Bottom")
		(5 "F.SilkS" user "Ref Des/Silkscreen Top")
		(7 "B.SilkS" user "Ref Des/Silkscreen Bottom")
		(1 "F.Mask" user "Board Geometry/Soldermask Top")
		(3 "B.Mask" user "Board Geometry/Soldermask Bottom")
		(17 "Dwgs.User" user "User.Drawings")
		(19 "Cmts.User" user "User.Comments")
		(21 "Eco1.User" user "User.Eco1")
		(23 "Eco2.User" user "User.Eco2")
		(25 "Edge.Cuts" user "Board Geometry/Outline")
		(27 "Margin" user)
		(31 "F.CrtYd" user "Package Geometry/Place Bound Top")
		(29 "B.CrtYd" user "Package Geometry/Place Bound Bottom")
		(35 "F.Fab" user "Ref Des/Assembly Top")
		(33 "B.Fab" user "Ref Des/Assembly Bottom")
	)
	(footprint ""
		(layer "B.Cu")
		(at 374.744742 -73.095104)
		(property "Reference" "C2P5"
			(at 0 0 0)
			(layer "B.SilkS")
			(hide yes)
			(effects
				(font
					(size 1.27 1.27)
				)
				(justify mirror)
			)
		)
		(property "Value" ""
			(at 0 0 0)
			(layer "B.Fab")
			(effects
				(font
					(size 1.27 1.27)
				)
				(justify mirror)
			)
		)
		(duplicate_pad_numbers_are_jumpers no)
		(fp_rect
			(start 0.2794 0.9144)
			(end -0.2794 -0.1143)
			(stroke
				(width 0)
				(type default)
			)
			(fill no)
			(layer "B.CrtYd")
		)
		(fp_line
			(start -0.2794 -0.1143)
			(end -0.2794 0.9144)
			(stroke
				(width 0.1)
				(type default)
			)
			(layer "B.Fab")
		)
		(fp_line
			(start -0.2794 0.9144)
			(end 0.2794 0.9144)
			(stroke
				(width 0.1)
				(type default)
			)
			(layer "B.Fab")
		)
		(fp_line
			(start 0.2794 -0.1143)
			(end -0.2794 -0.1143)
			(stroke
				(width 0.1)
				(type default)
			)
			(layer "B.Fab")
		)
		(fp_line
			(start 0.2794 0.9144)
			(end 0.2794 -0.1143)
			(stroke
				(width 0.1)
				(type default)
			)
			(layer "B.Fab")
		)
		(pad "1" smd custom
			(at 0 0 270)
			(size 0.10414 0.10414)
			(layers "B.Cu" "B.Mask" "B.Paste")
			(net "P3V3_STBY")
			(options
				(clearance outline)
				(anchor circle)
			)
			(primitives
				(gr_poly
					(pts
						(xy -0.20828 -0.08636) (xy -0.20828 0.08636) (xy -0.08636 0.20828) (xy 0.086614 0.20828) (xy 0.20828 0.086614)
						(xy 0.20828 -0.08636) (xy 0.08636 -0.20828) (xy -0.08636 -0.20828)
					)
					(width 0)
					(fill yes)
				)
			)
		)
		(pad "2" smd custom
			(at 0 0.8001 270)
			(size 0.10414 0.10414)
			(layers "B.Cu" "B.Mask" "B.Paste")
			(net "GND")
			(options
				(clearance outline)
				(anchor circle)
			)
			(primitives
				(gr_poly
					(pts
						(xy -0.20828 -0.08636) (xy -0.20828 0.08636) (xy -0.08636 0.20828) (xy 0.086614 0.20828) (xy 0.20828 0.086614)
						(xy 0.20828 -0.08636) (xy 0.08636 -0.20828) (xy -0.08636 -0.20828)
					)
					(width 0)
					(fill yes)
				)
			)
		)
		(zone
			(layer "B.Cu")
			(hatch none 0.5)
			(connect_pads
				(clearance 0)
			)
			(min_thickness 0.25)
			(keepout
				(tracks not_allowed)
				(vias allowed)
				(pads allowed)
				(copperpour not_allowed)
				(footprints allowed)
			)
			(placement
				(enabled no)
				(sheetname "")
			)
			(fill
				(thermal_gap 0.5)
				(thermal_bridge_width 0.5)
				(island_removal_mode 0)
			)
			(polygon
				(pts
					(xy 374.832372 -72.885554) (xy 374.832372 -72.504554) (xy 374.657112 -72.504554) (xy 374.656858 -72.885554)
				)
			)
		)
		(zone
			(layer "B.Cu")
			(hatch none 0.5)
			(connect_pads
				(clearance 0)
			)
			(min_thickness 0.25)
			(keepout
				(tracks allowed)
				(vias not_allowed)
				(pads allowed)
				(copperpour not_allowed)
				(footprints allowed)
			)
			(placement
				(enabled no)
				(sheetname "")
			)
			(fill
				(thermal_gap 0.5)
				(thermal_bridge_width 0.5)
				(island_removal_mode 0)
			)
			(polygon
				(pts
					(xy 374.832372 -72.885554) (xy 374.832372 -72.504554) (xy 374.657112 -72.504554) (xy 374.656858 -72.885554)
				)
			)
		)
	)
	(footprint ""
		(layer "B.Cu")
		(at 390.7155 -38.62451 -90)
		(property "Reference" "C2T4"
			(at 0 0 90)
			(layer "B.SilkS")
			(hide yes)
			(effects
				(font
					(size 1.27 1.27)
				)
				(justify mirror)
			)
		)
		(property "Value" ""
			(at 0 0 90)
			(layer "B.Fab")
			(effects
				(font
					(size 1.27 1.27)
				)
				(justify mirror)
			)
		)
		(duplicate_pad_numbers_are_jumpers no)
		(fp_poly
			(pts
				(xy -0.3048 -0.1016) (xy -0.3048 0.9906) (xy 0.3048 0.9906) (xy 0.3048 -0.1016)
			)
			(stroke
				(width 0)
				(type default)
			)
			(fill no)
			(layer "B.CrtYd")
		)
		(fp_line
			(start -0.3048 0.9906)
			(end -0.3048 -0.1016)
			(stroke
				(width 0.1)
				(type default)
			)
			(layer "B.Fab")
		)
		(fp_line
			(start 0.3048 0.9906)
			(end -0.3048 0.9906)
			(stroke
				(width 0.1)
				(type default)
			)
			(layer "B.Fab")
		)
		(fp_line
			(start -0.3048 -0.1016)
			(end 0.3048 -0.1016)
			(stroke
				(width 0.1)
				(type default)
			)
			(layer "B.Fab")
		)
		(fp_line
			(start 0.3048 -0.1016)
			(end 0.3048 0.9906)
			(stroke
				(width 0.1)
				(type default)
			)
			(layer "B.Fab")
		)
		(pad "1" smd rect
			(at 0 0 90)
			(size 0.508 0.508)
			(layers "B.Cu" "B.Mask" "B.Paste")
			(net "P3V3")
		)
		(pad "2" smd rect
			(at 0 0.889 90)
			(size 0.508 0.508)
			(layers "B.Cu" "B.Mask" "B.Paste")
			(net "GND")
		)
		(zone
			(layer "B.Cu")
			(hatch none 0.5)
			(connect_pads
				(clearance 0)
			)
			(min_thickness 0.25)
			(keepout
				(tracks not_allowed)
				(vias allowed)
				(pads allowed)
				(copperpour not_allowed)
				(footprints allowed)
			)
			(placement
				(enabled no)
				(sheetname "")
			)
			(fill
				(thermal_gap 0.5)
				(thermal_bridge_width 0.5)
				(island_removal_mode 0)
			)
			(polygon
				(pts
					(xy 390.0805 -38.37051) (xy 390.0805 -38.87851) (xy 390.4615 -38.87851) (xy 390.4615 -38.37051)
				)
			)
		)
		(zone
			(layer "B.Cu")
			(hatch none 0.5)
			(connect_pads
				(clearance 0)
			)
			(min_thickness 0.25)
			(keepout
				(tracks allowed)
				(vias not_allowed)
				(pads allowed)
				(copperpour not_allowed)
				(footprints allowed)
			)
			(placement
				(enabled no)
				(sheetname "")
			)
			(fill
				(thermal_gap 0.5)
				(thermal_bridge_width 0.5)
				(island_removal_mode 0)
			)
			(polygon
				(pts
					(xy 390.4615 -38.37051) (xy 390.4615 -38.87851) (xy 390.0805 -38.87851) (xy 390.0805 -38.37051)
				)
			)
		)
	)
	(footprint ""
		(layer "B.Cu")
		(at 161.78022 -123.0757 180)
		(property "Reference" "R7M4"
			(at 0 0 0)
			(layer "B.SilkS")
			(hide yes)
			(effects
				(font
					(size 1.27 1.27)
				)
				(justify mirror)
			)
		)
		(property "Value" ""
			(at 0 0 0)
			(layer "B.Fab")
			(effects
				(font
					(size 1.27 1.27)
				)
				(justify mirror)
			)
		)
		(duplicate_pad_numbers_are_jumpers no)
		(fp_poly
			(pts
				(xy 0.2794 -0.1016) (xy -0.2794 -0.1016) (xy -0.2794 0.9906) (xy 0.2794 0.9906)
			)
			(stroke
				(width 0)
				(type default)
			)
			(fill no)
			(layer "B.CrtYd")
		)
		(fp_line
			(start 0.2794 0.9906)
			(end -0.2794 0.9906)
			(stroke
				(width 0.1)
				(type default)
			)
			(layer "B.Fab")
		)
		(fp_line
			(start 0.2794 -0.1016)
			(end 0.2794 0.9906)
			(stroke
				(width 0.1)
				(type default)
			)
			(layer "B.Fab")
		)
		(fp_line
			(start -0.2794 0.9906)
			(end -0.2794 -0.1016)
			(stroke
				(width 0.1)
				(type default)
			)
			(layer "B.Fab")
		)
		(fp_line
			(start -0.2794 -0.1016)
			(end 0.2794 -0.1016)
			(stroke
				(width 0.1)
				(type default)
			)
			(layer "B.Fab")
		)
		(pad "1" smd rect
			(at 0 0)
			(size 0.508 0.508)
			(layers "B.Cu" "B.Mask" "B.Paste")
			(net "SMB_DDR_KLM_VPP_SCL_R")
		)
		(pad "2" smd rect
			(at 0 0.889)
			(size 0.508 0.508)
			(layers "B.Cu" "B.Mask" "B.Paste")
			(net "SMB_DDR_KLM_VPP_SCL")
		)
		(zone
			(layer "B.Cu")
			(hatch none 0.5)
			(connect_pads
				(clearance 0)
			)
			(min_thickness 0.25)
			(keepout
				(tracks not_allowed)
				(vias allowed)
				(pads allowed)
				(copperpour not_allowed)
				(footprints allowed)
			)
			(placement
				(enabled no)
				(sheetname "")
			)
			(fill
				(thermal_gap 0.5)
				(thermal_bridge_width 0.5)
				(island_removal_mode 0)
			)
			(polygon
				(pts
					(xy 161.52622 -123.7107) (xy 162.03422 -123.7107) (xy 162.03422 -123.3297) (xy 161.52622 -123.3297)
				)
			)
		)
		(zone
			(layer "B.Cu")
			(hatch none 0.5)
			(connect_pads
				(clearance 0)
			)
			(min_thickness 0.25)
			(keepout
				(tracks allowed)
				(vias not_allowed)
				(pads allowed)
				(copperpour not_allowed)
				(footprints allowed)
			)
			(placement
				(enabled no)
				(sheetname "")
			)
			(fill
				(thermal_gap 0.5)
				(thermal_bridge_width 0.5)
				(island_removal_mode 0)
			)
			(polygon
				(pts
					(xy 161.52622 -123.3297) (xy 162.03422 -123.3297) (xy 162.03422 -123.7107) (xy 161.52622 -123.7107)
				)
			)
		)
	)
)
